# S9S_MB_2U (Grand Teton) — schematic netlist excerpt (pin names and nets, part order shuffled) for the footprints in the layout excerpt that follows; sources: Cadence DE-HDL packaged netlist, KiCad conversion of 03242023_DA0F0TMBIJ0_F0T_Motherboard_J_brd_V01_OCP.brd

R4685  Q_RES  10.5K 1% EMPTY  pkg 0402LF  page 305 : A = P3V3_AUX ; B = P12V_HSC_TEMP_ALERT_R_N
PC1361  Q_CAP  0.1UF 25V 10% X7R  pkg 0402  page 287 : A = GND ; B = PVCCIN_CPU1_VREF

(kicad_pcb
	(version 20260206)
	(generator "pcbnew")
	(generator_version "10.0")
	(general
		(thickness 1.6)
		(legacy_teardrops no)
	)
	(paper "A4")
	(title_block
		(title "03242023_DA0F0TMBIJ0_F0T_Motherboard_J_brd_V01_OCP.brd")
		(comment 1 "Grand Teton / footprints 3461-3462 of 6105")
	)
	(layers
		(0 "F.Cu" signal "TOP")
		(4 "In1.Cu" signal "GND")
		(6 "In2.Cu" signal "IN1")
		(8 "In3.Cu" signal "GND1")
		(10 "In4.Cu" signal "IN2")
		(12 "In5.Cu" signal "GND2")
		(14 "In6.Cu" signal "IN3")
		(16 "In7.Cu" signal "GND3")
		(18 "In8.Cu" signal "VCC")
		(20 "In9.Cu" signal "VCC1")
		(22 "In10.Cu" signal "GND4")
		(24 "In11.Cu" signal "IN4")
		(26 "In12.Cu" signal "GND5")
		(28 "In13.Cu" signal "IN5")
		(30 "In14.Cu" signal "GND6")
		(32 "In15.Cu" signal "IN6")
		(34 "In16.Cu" signal "GND7")
		(2 "B.Cu" signal "BOTTOM")
		(9 "F.Adhes" user "F.Adhesive")
		(11 "B.Adhes" user "B.Adhesive")
		(13 "F.Paste" user "Package Geometry/Pastemask Top")
		(15 "B.Paste" user "Package Geometry/Pastemask Bottom")
		(5 "F.SilkS" user "Ref Des/Silkscreen Top")
		(7 "B.SilkS" user "Ref Des/Silkscreen Bottom")
		(1 "F.Mask" user "Board Geometry/Soldermask Top")
		(3 "B.Mask" user "Board Geometry/Soldermask Bottom")
		(17 "Dwgs.User" user "User.Drawings")
		(19 "Cmts.User" user "User.Comments")
		(21 "Eco1.User" user "User.Eco1")
		(23 "Eco2.User" user "User.Eco2")
		(25 "Edge.Cuts" user "Board Geometry/Outline")
		(27 "Margin" user)
		(31 "F.CrtYd" user "Package Geometry/Place Bound Top")
		(29 "B.CrtYd" user "Package Geometry/Place Bound Bottom")
		(35 "F.Fab" user "Ref Des/Assembly Top")
		(33 "B.Fab" user "Ref Des/Assembly Bottom")
	)
	(footprint ""
		(layer "F.Cu")
		(at 126.862332 -341.716106 -90)
		(property "Reference" "PC1361"
			(at 0 0 270)
			(layer "F.SilkS")
			(hide yes)
			(effects
				(font
					(size 1.27 1.27)
				)
			)
		)
		(property "Value" ""
			(at 0 0 270)
			(layer "F.Fab")
			(effects
				(font
					(size 1.27 1.27)
				)
			)
		)
		(duplicate_pad_numbers_are_jumpers no)
		(fp_line
			(start -0.7874 0.4064)
			(end -0.7874 -0.4064)
			(stroke
				(width 0.1524)
				(type default)
			)
			(layer "F.SilkS")
		)
		(fp_line
			(start 0.7874 0.4064)
			(end -0.7874 0.4064)
			(stroke
				(width 0.1524)
				(type default)
			)
			(layer "F.SilkS")
		)
		(fp_line
			(start -0.7874 -0.4064)
			(end 0.7874 -0.4064)
			(stroke
				(width 0.1524)
				(type default)
			)
			(layer "F.SilkS")
		)
		(fp_line
			(start 0.7874 -0.4064)
			(end 0.7874 0.4064)
			(stroke
				(width 0.1524)
				(type default)
			)
			(layer "F.SilkS")
		)
		(fp_line
			(start -0.67945 0.3048)
			(end -0.67945 -0.305054)
			(stroke
				(width 0.1)
				(type default)
			)
			(layer "F.Fab")
		)
		(fp_line
			(start -0.12065 0.3048)
			(end -0.67945 0.3048)
			(stroke
				(width 0.1)
				(type default)
			)
			(layer "F.Fab")
		)
		(fp_line
			(start 0.120396 0.3048)
			(end 0.120396 0.2794)
			(stroke
				(width 0.1)
				(type default)
			)
			(layer "F.Fab")
		)
		(fp_line
			(start 0.67945 0.3048)
			(end 0.120396 0.3048)
			(stroke
				(width 0.1)
				(type default)
			)
			(layer "F.Fab")
		)
		(fp_line
			(start -0.12065 0.2794)
			(end -0.12065 0.3048)
			(stroke
				(width 0.1)
				(type default)
			)
			(layer "F.Fab")
		)
		(fp_line
			(start 0.120396 0.2794)
			(end -0.12065 0.2794)
			(stroke
				(width 0.1)
				(type default)
			)
			(layer "F.Fab")
		)
		(fp_line
			(start -0.12065 -0.2794)
			(end 0.12065 -0.2794)
			(stroke
				(width 0.1)
				(type default)
			)
			(layer "F.Fab")
		)
		(fp_line
			(start 0.12065 -0.2794)
			(end 0.12065 -0.3048)
			(stroke
				(width 0.1)
				(type default)
			)
			(layer "F.Fab")
		)
		(fp_line
			(start 0.12065 -0.3048)
			(end 0.67945 -0.3048)
			(stroke
				(width 0.1)
				(type default)
			)
			(layer "F.Fab")
		)
		(fp_line
			(start 0.67945 -0.3048)
			(end 0.67945 0.3048)
			(stroke
				(width 0.1)
				(type default)
			)
			(layer "F.Fab")
		)
		(fp_line
			(start -0.67945 -0.305054)
			(end -0.12065 -0.305054)
			(stroke
				(width 0.1)
				(type default)
			)
			(layer "F.Fab")
		)
		(fp_line
			(start -0.12065 -0.305054)
			(end -0.12065 -0.2794)
			(stroke
				(width 0.1)
				(type default)
			)
			(layer "F.Fab")
		)
		(pad "1" smd circle
			(at -0.40005 0 270)
			(size 0 0)
			(layers "F.Cu" "F.Mask" "F.Paste")
			(net "GND")
		)
		(pad "2" smd circle
			(at 0.40005 0 270)
			(size 0 0)
			(layers "F.Cu" "F.Mask" "F.Paste")
			(net "PVCCIN_CPU1_VREF")
		)
	)
	(footprint ""
		(layer "F.Cu")
		(at 298.16552 -406.6794)
		(property "Reference" "R4685"
			(at 0 0 0)
			(layer "F.SilkS")
			(hide yes)
			(effects
				(font
					(size 1.27 1.27)
				)
			)
		)
		(property "Value" ""
			(at 0 0 0)
			(layer "F.Fab")
			(effects
				(font
					(size 1.27 1.27)
				)
			)
		)
		(duplicate_pad_numbers_are_jumpers no)
		(fp_line
			(start -0.7874 -0.4064)
			(end 0.7874 -0.4064)
			(stroke
				(width 0.1524)
				(type default)
			)
			(layer "F.SilkS")
		)
		(fp_line
			(start -0.7874 0.4064)
			(end -0.7874 -0.4064)
			(stroke
				(width 0.1524)
				(type default)
			)
			(layer "F.SilkS")
		)
		(fp_line
			(start 0.7874 -0.4064)
			(end 0.7874 0.4064)
			(stroke
				(width 0.1524)
				(type default)
			)
			(layer "F.SilkS")
		)
		(fp_line
			(start 0.7874 0.4064)
			(end -0.7874 0.4064)
			(stroke
				(width 0.1524)
				(type default)
			)
			(layer "F.SilkS")
		)
		(fp_line
			(start -0.67945 -0.305054)
			(end -0.12065 -0.305054)
			(stroke
				(width 0.1)
				(type default)
			)
			(layer "F.Fab")
		)
		(fp_line
			(start -0.67945 0.3048)
			(end -0.67945 -0.305054)
			(stroke
				(width 0.1)
				(type default)
			)
			(layer "F.Fab")
		)
		(fp_line
			(start -0.12065 -0.305054)
			(end -0.12065 -0.2794)
			(stroke
				(width 0.1)
				(type default)
			)
			(layer "F.Fab")
		)
		(fp_line
			(start -0.12065 -0.2794)
			(end 0.12065 -0.2794)
			(stroke
				(width 0.1)
				(type default)
			)
			(layer "F.Fab")
		)
		(fp_line
			(start -0.12065 0.2794)
			(end -0.12065 0.3048)
			(stroke
				(width 0.1)
				(type default)
			)
			(layer "F.Fab")
		)
		(fp_line
			(start -0.12065 0.3048)
			(end -0.67945 0.3048)
			(stroke
				(width 0.1)
				(type default)
			)
			(layer "F.Fab")
		)
		(fp_line
			(start 0.120396 0.2794)
			(end -0.12065 0.2794)
			(stroke
				(width 0.1)
				(type default)
			)
			(layer "F.Fab")
		)
		(fp_line
			(start 0.120396 0.3048)
			(end 0.120396 0.2794)
			(stroke
				(width 0.1)
				(type default)
			)
			(layer "F.Fab")
		)
		(fp_line
			(start 0.12065 -0.3048)
			(end 0.67945 -0.3048)
			(stroke
				(width 0.1)
				(type default)
			)
			(layer "F.Fab")
		)
		(fp_line
			(start 0.12065 -0.2794)
			(end 0.12065 -0.3048)
			(stroke
				(width 0.1)
				(type default)
			)
			(layer "F.Fab")
		)
		(fp_line
			(start 0.67945 -0.3048)
			(end 0.67945 0.3048)
			(stroke
				(width 0.1)
				(type default)
			)
			(layer "F.Fab")
		)
		(fp_line
			(start 0.67945 0.3048)
			(end 0.120396 0.3048)
			(stroke
				(width 0.1)
				(type default)
			)
			(layer "F.Fab")
		)
		(pad "1" smd circle
			(at -0.40005 0)
			(size 0 0)
			(layers "F.Cu" "F.Mask" "F.Paste")
			(net "P3V3_AUX")
		)
		(pad "2" smd circle
			(at 0.40005 0)
			(size 0 0)
			(layers "F.Cu" "F.Mask" "F.Paste")
			(net "P12V_HSC_TEMP_ALERT_R_N")
		)
	)
)
